(kicad_pcb
	(version 20260206)
	(generator "pcbnew")
	(generator_version "10.0")
	(general
		(thickness 1.6)
		(legacy_teardrops no)
	)
	(paper "A4")
	(title_block
		(title "04192023_DAF0TMB3IC0_F0TG_MB_C_brd_V02_OCP.brd")
		(comment 1 "Grand Teton / footprints 4611-4611 of 8354")
	)
	(layers
		(0 "F.Cu" signal "TOP")
		(4 "In1.Cu" signal "GND")
		(6 "In2.Cu" signal "IN1")
		(8 "In3.Cu" signal "GND1")
		(10 "In4.Cu" signal "IN2")
		(12 "In5.Cu" signal "GND2")
		(14 "In6.Cu" signal "IN3")
		(16 "In7.Cu" signal "GND3")
		(18 "In8.Cu" signal "VCC")
		(20 "In9.Cu" signal "VCC1")
		(22 "In10.Cu" signal "GND4")
		(24 "In11.Cu" signal "IN4")
		(26 "In12.Cu" signal "GND5")
		(28 "In13.Cu" signal "IN5")
		(30 "In14.Cu" signal "GND6")
		(32 "In15.Cu" signal "IN6")
		(34 "In16.Cu" signal "GND7")
		(2 "B.Cu" signal "BOTTOM")
		(9 "F.Adhes" user "F.Adhesive")
		(11 "B.Adhes" user "B.Adhesive")
		(13 "F.Paste" user "Package Geometry/Pastemask Top")
		(15 "B.Paste" user "Package Geometry/Pastemask Bottom")
		(5 "F.SilkS" user "Ref Des/Silkscreen Top")
		(7 "B.SilkS" user "Ref Des/Silkscreen Bottom")
		(1 "F.Mask" user "Board Geometry/Soldermask Top")
		(3 "B.Mask" user "Board Geometry/Soldermask Bottom")
		(17 "Dwgs.User" user "User.Drawings")
		(19 "Cmts.User" user "User.Comments")
		(21 "Eco1.User" user "User.Eco1")
		(23 "Eco2.User" user "User.Eco2")
		(25 "Edge.Cuts" user "Board Geometry/Outline")
		(27 "Margin" user)
		(31 "F.CrtYd" user "Package Geometry/Place Bound Top")
		(29 "B.CrtYd" user "Package Geometry/Place Bound Bottom")
		(35 "F.Fab" user "Ref Des/Assembly Top")
		(33 "B.Fab" user "Ref Des/Assembly Bottom")
	)
	(footprint ""
		(layer "F.Cu")
		(at 36.881054 -346.721176)
		(property "Reference" "PU52"
			(at -2.972054 -7.709154 0)
			(unlocked yes)
			(layer "F.SilkS")
			(effects
				(font
					(size 0.7874 0.5842)
					(thickness 0.1524)
				)
				(justify left)
			)
		)
		(property "Value" ""
			(at 0 0 0)
			(layer "F.Fab")
			(effects
				(font
					(size 1.27 1.27)
				)
			)
		)
		(duplicate_pad_numbers_are_jumpers no)
		(fp_line
			(start -2.500122 -2.999994)
			(end -2.24409 -2.999994)
			(stroke
				(width 0.1524)
				(type default)
			)
			(layer "F.SilkS")
		)
		(fp_line
			(start -2.500122 -2.529078)
			(end -2.500122 -2.999994)
			(stroke
				(width 0.1524)
				(type default)
			)
			(layer "F.SilkS")
		)
		(fp_line
			(start -2.500122 0.6604)
			(end -2.500122 0.229108)
			(stroke
				(width 0.1524)
				(type default)
			)
			(layer "F.SilkS")
		)
		(fp_line
			(start -2.500122 2.999994)
			(end -2.500122 2.339594)
			(stroke
				(width 0.1524)
				(type default)
			)
			(layer "F.SilkS")
		)
		(fp_line
			(start -2.2987 2.999994)
			(end -2.500122 2.999994)
			(stroke
				(width 0.1524)
				(type default)
			)
			(layer "F.SilkS")
		)
		(fp_line
			(start 2.31394 -2.999994)
			(end 2.500122 -2.999994)
			(stroke
				(width 0.1524)
				(type default)
			)
			(layer "F.SilkS")
		)
		(fp_line
			(start 2.500122 -2.999994)
			(end 2.500122 -2.44348)
			(stroke
				(width 0.1524)
				(type default)
			)
			(layer "F.SilkS")
		)
		(fp_line
			(start 2.500122 2.339594)
			(end 2.500122 2.999994)
			(stroke
				(width 0.1524)
				(type default)
			)
			(layer "F.SilkS")
		)
		(fp_line
			(start 2.500122 2.999994)
			(end 2.2987 2.999994)
			(stroke
				(width 0.1524)
				(type default)
			)
			(layer "F.SilkS")
		)
		(fp_poly
			(pts
				(xy -2.785872 -2.44094) (xy -3.45948 -2.665476) (xy -3.010408 -3.114548)
			)
			(stroke
				(width 0)
				(type default)
			)
			(fill yes)
			(layer "F.SilkS")
		)
		(fp_line
			(start -2.500122 -2.999994)
			(end 2.500122 -2.999994)
			(stroke
				(width 0.1)
				(type default)
			)
			(layer "F.Fab")
		)
		(fp_line
			(start -2.500122 2.999994)
			(end -2.500122 -2.999994)
			(stroke
				(width 0.1)
				(type default)
			)
			(layer "F.Fab")
		)
		(fp_line
			(start 2.500122 -2.999994)
			(end 2.500122 2.999994)
			(stroke
				(width 0.1)
				(type default)
			)
			(layer "F.Fab")
		)
		(fp_line
			(start 2.500122 2.999994)
			(end -2.500122 2.999994)
			(stroke
				(width 0.1)
				(type default)
			)
			(layer "F.Fab")
		)
		(fp_poly
			(pts
				(xy -4.218432 -2.783078) (xy -4.218432 -1.767078) (xy -3.202432 -2.275078)
			)
			(stroke
				(width 0)
				(type default)
			)
			(fill yes)
			(layer "F.Fab")
		)
		(pad "1" smd rect
			(at -2.400046 -2.275078 90)
			(size 0.2286 0.6096)
			(layers "F.Cu" "F.Mask" "F.Paste")
			(net "PVDDIO_P1_VOS3")
		)
		(pad "2" smd rect
			(at -2.400046 -1.82499 90)
			(size 0.2286 0.6096)
			(layers "F.Cu" "F.Mask" "F.Paste")
			(net "GND")
		)
		(pad "3" smd rect
			(at -2.400046 -1.374902 90)
			(size 0.2286 0.6096)
			(layers "F.Cu" "F.Mask" "F.Paste")
			(net "PVDDIO_P1_VCC3")
		)
		(pad "4" smd rect
			(at -2.400046 -0.925068 90)
			(size 0.2286 0.6096)
			(layers "F.Cu" "F.Mask" "F.Paste")
			(net "PVDDCR_CPU1_P1_PVCC")
		)
		(pad "5" smd rect
			(at -2.400046 -0.47498 90)
			(size 0.2286 0.6096)
			(layers "F.Cu" "F.Mask" "F.Paste")
			(net "GND")
		)
		(pad "6" smd rect
			(at -2.400046 -0.024892 90)
			(size 0.2286 0.6096)
			(layers "F.Cu" "F.Mask" "F.Paste")
			(net "NC_PVDDIO_P1_GL1_3")
		)
		(pad "7_9-20_24" smd circle
			(at 0 1.150112 90)
			(size 0 0)
			(layers "F.Cu" "F.Mask" "F.Paste")
			(net "GND")
		)
		(pad "10_19" smd rect
			(at 0 2.899918 90)
			(size 0.6096 4.318)
			(layers "F.Cu" "F.Mask" "F.Paste")
			(net "SW_PVDDIO_P1_SW3")
		)
		(pad "25_29" smd rect
			(at 1.549908 -1.279906 270)
			(size 2.0574 2.3114)
			(layers "F.Cu" "F.Mask" "F.Paste")
			(net "SW_P12V_AUX_PVDDIO_P1_FLT")
		)
		(pad "30" smd rect
			(at 2.05994 -2.899918)
			(size 0.2286 0.6096)
			(layers "F.Cu" "F.Mask" "F.Paste")
			(net "SW_P12V_AUX_PVDDIO_P1_FLT")
		)
		(pad "31" smd rect
			(at 1.610106 -2.899918)
			(size 0.2286 0.6096)
			(layers "F.Cu" "F.Mask" "F.Paste")
			(net "NC_PVDDIO_P1_DNC3")
		)
		(pad "32" smd rect
			(at 1.160018 -2.899918)
			(size 0.2286 0.6096)
			(layers "F.Cu" "F.Mask" "F.Paste")
			(net "SW_PVDDIO_P1_BOOTR3")
		)
		(pad "33" smd rect
			(at 0.70993 -2.899918)
			(size 0.2286 0.6096)
			(layers "F.Cu" "F.Mask" "F.Paste")
			(net "SW_PVDDIO_P1_BOOT3")
		)
		(pad "34" smd rect
			(at 0.260096 -2.899918)
			(size 0.2286 0.6096)
			(layers "F.Cu" "F.Mask" "F.Paste")
			(net "PVDDIO_P1_PWM3")
		)
		(pad "35" smd rect
			(at -0.189992 -2.899918)
			(size 0.2286 0.6096)
			(layers "F.Cu" "F.Mask" "F.Paste")
			(net "PVDDIO_P1_VCC3")
		)
		(pad "36" smd rect
			(at -0.64008 -2.899918)
			(size 0.2286 0.6096)
			(layers "F.Cu" "F.Mask" "F.Paste")
			(net "PVDDIO_P1_TEMP1")
		)
		(pad "37" smd rect
			(at -1.089914 -2.899918)
			(size 0.2286 0.6096)
			(layers "F.Cu" "F.Mask" "F.Paste")
			(net "PVDDIO_P1_LSET3")
		)
		(pad "38" smd rect
			(at -1.540002 -2.899918)
			(size 0.2286 0.6096)
			(layers "F.Cu" "F.Mask" "F.Paste")
			(net "PVDDIO_P1_IMON3")
		)
		(pad "39" smd rect
			(at -1.99009 -2.899918)
			(size 0.2286 0.6096)
			(layers "F.Cu" "F.Mask" "F.Paste")
			(net "PVDDCR_CPU1_P1_VCCS")
		)
		(pad "40" smd rect
			(at -0.87503 -1.27508)
			(size 1.7526 1.9558)
			(layers "F.Cu" "F.Mask" "F.Paste")
			(net "GND")
		)
		(pad "41" smd rect
			(at -1.525016 0.249936 270)
			(size 0.3048 0.4572)
			(layers "F.Cu" "F.Mask" "F.Paste")
			(net "NC_PVDDIO_P1_GL2_3")
		)
		(zone
			(layer "F.Cu")
			(hatch none 0.5)
			(connect_pads
				(clearance 0)
			)
			(min_thickness 0.25)
			(keepout
				(tracks not_allowed)
				(vias allowed)
				(pads allowed)
				(copperpour not_allowed)
				(footprints allowed)
			)
			(placement
				(enabled no)
				(sheetname "")
			)
			(fill
				(thermal_gap 0.5)
				(thermal_bridge_width 0.5)
				(island_removal_mode 0)
			)
			(polygon
				(pts
					(xy 34.836608 -347.4212) (xy 34.836608 -348.382082) (xy 35.078924 -348.382082) (xy 35.078924 -347.4212)
				)
			)
		)
		(zone
			(layer "F.Cu")
			(hatch none 0.5)
			(connect_pads
				(clearance 0)
			)
			(min_thickness 0.25)
			(keepout
				(tracks not_allowed)
				(vias allowed)
				(pads allowed)
				(copperpour not_allowed)
				(footprints allowed)
			)
			(placement
				(enabled no)
				(sheetname "")
			)
			(fill
				(thermal_gap 0.5)
				(thermal_bridge_width 0.5)
				(island_removal_mode 0)
			)
			(polygon
				(pts
					(xy 34.380932 -344.138758) (xy 34.380932 -344.470482) (xy 39.381176 -344.470482) (xy 39.381176 -344.147648)
					(xy 39.090854 -344.147648) (xy 39.090854 -344.176858) (xy 34.671254 -344.176858) (xy 34.671254 -344.138758)
				)
			)
		)
	)
)
